# T6G (Grand Teton) — schematic netlist excerpt (pin names and nets, part order shuffled) for the footprints in the layout excerpt that follows; sources: Cadence DE-HDL packaged netlist, KiCad conversion of 04192023_DAF0TMB3IC0_F0TG_MB_C_brd_V02_OCP.brd

R1188  Q_RES  1K 1% CHIP  pkg 0402LF  page 83 : A = PVDDCR_CPU1_P1_SMB_ALERT ; B = P3V3_AUX
PR195  Q_RES  8.87K 1% EMPTY  pkg 0402LF  page 212 : A = GND ; B = PVDDCR_CPU0_P1_LSET3

(kicad_pcb
	(version 20260206)
	(generator "pcbnew")
	(generator_version "10.0")
	(general
		(thickness 1.6)
		(legacy_teardrops no)
	)
	(paper "A4")
	(title_block
		(title "04192023_DAF0TMB3IC0_F0TG_MB_C_brd_V02_OCP.brd")
		(comment 1 "Grand Teton / footprints 2344-2345 of 8354")
	)
	(layers
		(0 "F.Cu" signal "TOP")
		(4 "In1.Cu" signal "GND")
		(6 "In2.Cu" signal "IN1")
		(8 "In3.Cu" signal "GND1")
		(10 "In4.Cu" signal "IN2")
		(12 "In5.Cu" signal "GND2")
		(14 "In6.Cu" signal "IN3")
		(16 "In7.Cu" signal "GND3")
		(18 "In8.Cu" signal "VCC")
		(20 "In9.Cu" signal "VCC1")
		(22 "In10.Cu" signal "GND4")
		(24 "In11.Cu" signal "IN4")
		(26 "In12.Cu" signal "GND5")
		(28 "In13.Cu" signal "IN5")
		(30 "In14.Cu" signal "GND6")
		(32 "In15.Cu" signal "IN6")
		(34 "In16.Cu" signal "GND7")
		(2 "B.Cu" signal "BOTTOM")
		(9 "F.Adhes" user "F.Adhesive")
		(11 "B.Adhes" user "B.Adhesive")
		(13 "F.Paste" user "Package Geometry/Pastemask Top")
		(15 "B.Paste" user "Package Geometry/Pastemask Bottom")
		(5 "F.SilkS" user "Ref Des/Silkscreen Top")
		(7 "B.SilkS" user "Ref Des/Silkscreen Bottom")
		(1 "F.Mask" user "Board Geometry/Soldermask Top")
		(3 "B.Mask" user "Board Geometry/Soldermask Bottom")
		(17 "Dwgs.User" user "User.Drawings")
		(19 "Cmts.User" user "User.Comments")
		(21 "Eco1.User" user "User.Eco1")
		(23 "Eco2.User" user "User.Eco2")
		(25 "Edge.Cuts" user "Board Geometry/Outline")
		(27 "Margin" user)
		(31 "F.CrtYd" user "Package Geometry/Place Bound Top")
		(29 "B.CrtYd" user "Package Geometry/Place Bound Bottom")
		(35 "F.Fab" user "Ref Des/Assembly Top")
		(33 "B.Fab" user "Ref Des/Assembly Bottom")
	)
	(footprint ""
		(layer "F.Cu")
		(at 184.785 -100.294948 -90)
		(property "Reference" "R1188"
			(at 0 0 270)
			(layer "F.SilkS")
			(hide yes)
			(effects
				(font
					(size 1.27 1.27)
				)
			)
		)
		(property "Value" ""
			(at 0 0 270)
			(layer "F.Fab")
			(effects
				(font
					(size 1.27 1.27)
				)
			)
		)
		(duplicate_pad_numbers_are_jumpers no)
		(fp_line
			(start -0.7874 0.4064)
			(end -0.7874 -0.4064)
			(stroke
				(width 0.1524)
				(type default)
			)
			(layer "F.SilkS")
		)
		(fp_line
			(start 0.7874 0.4064)
			(end -0.7874 0.4064)
			(stroke
				(width 0.1524)
				(type default)
			)
			(layer "F.SilkS")
		)
		(fp_line
			(start -0.7874 -0.4064)
			(end 0.7874 -0.4064)
			(stroke
				(width 0.1524)
				(type default)
			)
			(layer "F.SilkS")
		)
		(fp_line
			(start 0.7874 -0.4064)
			(end 0.7874 0.4064)
			(stroke
				(width 0.1524)
				(type default)
			)
			(layer "F.SilkS")
		)
		(fp_line
			(start -0.67945 0.3048)
			(end -0.67945 -0.305054)
			(stroke
				(width 0.1)
				(type default)
			)
			(layer "F.Fab")
		)
		(fp_line
			(start -0.12065 0.3048)
			(end -0.67945 0.3048)
			(stroke
				(width 0.1)
				(type default)
			)
			(layer "F.Fab")
		)
		(fp_line
			(start 0.120396 0.3048)
			(end 0.120396 0.2794)
			(stroke
				(width 0.1)
				(type default)
			)
			(layer "F.Fab")
		)
		(fp_line
			(start 0.67945 0.3048)
			(end 0.120396 0.3048)
			(stroke
				(width 0.1)
				(type default)
			)
			(layer "F.Fab")
		)
		(fp_line
			(start -0.12065 0.2794)
			(end -0.12065 0.3048)
			(stroke
				(width 0.1)
				(type default)
			)
			(layer "F.Fab")
		)
		(fp_line
			(start 0.120396 0.2794)
			(end -0.12065 0.2794)
			(stroke
				(width 0.1)
				(type default)
			)
			(layer "F.Fab")
		)
		(fp_line
			(start -0.12065 -0.2794)
			(end 0.12065 -0.2794)
			(stroke
				(width 0.1)
				(type default)
			)
			(layer "F.Fab")
		)
		(fp_line
			(start 0.12065 -0.2794)
			(end 0.12065 -0.3048)
			(stroke
				(width 0.1)
				(type default)
			)
			(layer "F.Fab")
		)
		(fp_line
			(start 0.12065 -0.3048)
			(end 0.67945 -0.3048)
			(stroke
				(width 0.1)
				(type default)
			)
			(layer "F.Fab")
		)
		(fp_line
			(start 0.67945 -0.3048)
			(end 0.67945 0.3048)
			(stroke
				(width 0.1)
				(type default)
			)
			(layer "F.Fab")
		)
		(fp_line
			(start -0.67945 -0.305054)
			(end -0.12065 -0.305054)
			(stroke
				(width 0.1)
				(type default)
			)
			(layer "F.Fab")
		)
		(fp_line
			(start -0.12065 -0.305054)
			(end -0.12065 -0.2794)
			(stroke
				(width 0.1)
				(type default)
			)
			(layer "F.Fab")
		)
		(pad "1" smd circle
			(at -0.40005 0 270)
			(size 0 0)
			(layers "F.Cu" "F.Mask" "F.Paste")
			(net "PVDDCR_CPU1_P1_SMB_ALERT")
		)
		(pad "2" smd circle
			(at 0.40005 0 270)
			(size 0 0)
			(layers "F.Cu" "F.Mask" "F.Paste")
			(net "P3V3_AUX")
		)
	)
	(footprint ""
		(layer "F.Cu")
		(at 100.378514 -177.481484)
		(property "Reference" "PR195"
			(at 0 0 0)
			(layer "F.SilkS")
			(hide yes)
			(effects
				(font
					(size 1.27 1.27)
				)
			)
		)
		(property "Value" ""
			(at 0 0 0)
			(layer "F.Fab")
			(effects
				(font
					(size 1.27 1.27)
				)
			)
		)
		(duplicate_pad_numbers_are_jumpers no)
		(fp_line
			(start -0.7874 -0.4064)
			(end 0.7874 -0.4064)
			(stroke
				(width 0.1524)
				(type default)
			)
			(layer "F.SilkS")
		)
		(fp_line
			(start -0.7874 0.4064)
			(end -0.7874 -0.4064)
			(stroke
				(width 0.1524)
				(type default)
			)
			(layer "F.SilkS")
		)
		(fp_line
			(start 0.7874 -0.4064)
			(end 0.7874 0.4064)
			(stroke
				(width 0.1524)
				(type default)
			)
			(layer "F.SilkS")
		)
		(fp_line
			(start 0.7874 0.4064)
			(end -0.7874 0.4064)
			(stroke
				(width 0.1524)
				(type default)
			)
			(layer "F.SilkS")
		)
		(fp_line
			(start -0.67945 -0.305054)
			(end -0.12065 -0.305054)
			(stroke
				(width 0.1)
				(type default)
			)
			(layer "F.Fab")
		)
		(fp_line
			(start -0.67945 0.3048)
			(end -0.67945 -0.305054)
			(stroke
				(width 0.1)
				(type default)
			)
			(layer "F.Fab")
		)
		(fp_line
			(start -0.12065 -0.305054)
			(end -0.12065 -0.2794)
			(stroke
				(width 0.1)
				(type default)
			)
			(layer "F.Fab")
		)
		(fp_line
			(start -0.12065 -0.2794)
			(end 0.12065 -0.2794)
			(stroke
				(width 0.1)
				(type default)
			)
			(layer "F.Fab")
		)
		(fp_line
			(start -0.12065 0.2794)
			(end -0.12065 0.3048)
			(stroke
				(width 0.1)
				(type default)
			)
			(layer "F.Fab")
		)
		(fp_line
			(start -0.12065 0.3048)
			(end -0.67945 0.3048)
			(stroke
				(width 0.1)
				(type default)
			)
			(layer "F.Fab")
		)
		(fp_line
			(start 0.120396 0.2794)
			(end -0.12065 0.2794)
			(stroke
				(width 0.1)
				(type default)
			)
			(layer "F.Fab")
		)
		(fp_line
			(start 0.120396 0.3048)
			(end 0.120396 0.2794)
			(stroke
				(width 0.1)
				(type default)
			)
			(layer "F.Fab")
		)
		(fp_line
			(start 0.12065 -0.3048)
			(end 0.67945 -0.3048)
			(stroke
				(width 0.1)
				(type default)
			)
			(layer "F.Fab")
		)
		(fp_line
			(start 0.12065 -0.2794)
			(end 0.12065 -0.3048)
			(stroke
				(width 0.1)
				(type default)
			)
			(layer "F.Fab")
		)
		(fp_line
			(start 0.67945 -0.3048)
			(end 0.67945 0.3048)
			(stroke
				(width 0.1)
				(type default)
			)
			(layer "F.Fab")
		)
		(fp_line
			(start 0.67945 0.3048)
			(end 0.120396 0.3048)
			(stroke
				(width 0.1)
				(type default)
			)
			(layer "F.Fab")
		)
		(pad "1" smd circle
			(at -0.40005 0)
			(size 0 0)
			(layers "F.Cu" "F.Mask" "F.Paste")
			(net "GND")
		)
		(pad "2" smd circle
			(at 0.40005 0)
			(size 0 0)
			(layers "F.Cu" "F.Mask" "F.Paste")
			(net "PVDDCR_CPU0_P1_LSET3")
		)
	)
)
